FILE_TYPE = CONNECTIVITY;
{Allegro Design Entry HDL 17.2-2016 S081 (4005846) 1/11/2022}
"PAGE_NUMBER" = 75;
0"NC";
1"PVCCINFAON_CPU0\g";
2"PVCCFA_EHV_CPU0\g";
3"PVCCFA_EHV_FIVRA_CPU0\g";
4"PVCCD_HV_CPU0\g";
5"PVCCIN_CPU0\g";
6"PVCCIN_CPU0\g";
7"PVPP_HBM_CPU0\g";
8"PVNN_MAIN_CPU0\g";
9"PVCCIN_CPU0\g";
10"GND\g";
11"GND\g";
12"GND\g";
13"GND\g";
14"GND\g";
15"GND\g";
16"GND\g";
17"GND\g";
18"GND\g";
%"Q_CAP"
"1","(-4425,-2225)","0","pure_quanta","I1";
;
PART_NUMBER"CH647KMEA04"
VOLTAGE"4V"
TOLERANCE"20%"
PACK_TYPE"C0805"
VALUE"47UF"
MATERIAL"X6S"
$LOCATION"C493"
CDS_LIB"pure_quanta"
CDS_LOCATION"C493"
$SEC"1"
CDS_SEC"1";
"B"
$PN"2"10;
"A"
$PN"1"3;
%"UNIVERSAL_POWER"
"1","(-4425,-950)","0","logical_power","I10";
;
HDL_POWER"PVCCINFAON_CPU0"
CDS_LIB"logical_power";
"A"1;
%"Q_CAP"
"1","(-4425,-250)","0","pure_quanta","I11";
;
PART_NUMBER"CH647KMEA04"
PACK_TYPE"C0805"
VALUE"47UF"
VOLTAGE"4V"
MATERIAL"X6S"
TOLERANCE"20%"
$LOCATION"C492"
CDS_LIB"pure_quanta"
CDS_LOCATION"C492"
$SEC"1"
CDS_SEC"1";
"B"
$PN"2"12;
"A"
$PN"1"2;
%"UNIVERSAL_POWER"
"1","(-4425,25)","0","logical_power","I12";
;
HDL_POWER"PVCCFA_EHV_CPU0"
CDS_LIB"logical_power";
"A"2;
%"Q_CAP"
"1","(-4425,725)","0","pure_quanta","I13";
;
PART_NUMBER"CH647KMEA04"
VALUE"47UF"
VOLTAGE"4V"
TOLERANCE"20%"
PACK_TYPE"C0805"
MATERIAL"X6S"
$LOCATION"C491"
CDS_LIB"pure_quanta"
CDS_LOCATION"C491"
$SEC"1"
CDS_SEC"1";
"B"
$PN"2"13;
"A"
$PN"1"4;
%"Q_CAP"
"1","(-3975,-1225)","0","pure_quanta","I14";
;
PART_NUMBER"CH647LME900"
VOLTAGE"2.5V"
MATERIAL"X6S"
PACK_TYPE"C0603"
VALUE"47UF"
TOLERANCE"20%"
$LOCATION"C532"
CDS_LIB"pure_quanta"
CDS_LOCATION"C532"
$SEC"1"
CDS_SEC"1";
"B"
$PN"2"11;
"A"
$PN"1"1;
%"UNIVERSAL_GND"
"1","(-3975,-600)","0","logical_power","I15";
;
CDS_LIB"logical_power"
HDL_POWER"GND";
"A"12;
%"Q_CAP"
"1","(-3975,-250)","0","pure_quanta","I16";
;
PART_NUMBER"CH647KMEA04"
PACK_TYPE"C0805"
VALUE"47UF"
VOLTAGE"4V"
MATERIAL"X6S"
TOLERANCE"20%"
$LOCATION"C496"
CDS_LIB"pure_quanta"
CDS_LOCATION"C496"
$SEC"1"
CDS_SEC"1";
"B"
$PN"2"12;
"A"
$PN"1"2;
%"Q_CAP"
"1","(-3525,-1225)","0","pure_quanta","I17";
;
PART_NUMBER"CH647LME900"
TOLERANCE"20%"
VOLTAGE"2.5V"
MATERIAL"X6S"
PACK_TYPE"C0603"
VALUE"47UF"
$LOCATION"C533"
CDS_LIB"pure_quanta"
CDS_LOCATION"C533"
$SEC"1"
CDS_SEC"1";
"B"
$PN"2"11;
"A"
$PN"1"1;
%"Q_CAP"
"1","(-3975,725)","0","pure_quanta","I18";
;
PART_NUMBER"CH647KMEA04"
VALUE"47UF"
VOLTAGE"4V"
TOLERANCE"20%"
PACK_TYPE"C0805"
MATERIAL"X6S"
$LOCATION"C495"
CDS_LIB"pure_quanta"
CDS_LOCATION"C495"
$SEC"1"
CDS_SEC"1";
"B"
$PN"2"13;
"A"
$PN"1"4;
%"Q_CAP"
"1","(-3525,725)","0","pure_quanta","I19";
;
PART_NUMBER"CH647KMEA04"
VALUE"47UF"
VOLTAGE"4V"
TOLERANCE"20%"
PACK_TYPE"C0805"
MATERIAL"X6S"
$LOCATION"C515"
CDS_LIB"pure_quanta"
CDS_LOCATION"C515"
$SEC"1"
CDS_SEC"1";
"B"
$PN"2"13;
"A"
$PN"1"4;
%"UNIVERSAL_POWER"
"1","(-4425,-1950)","0","logical_power","I2";
;
HDL_POWER"PVCCFA_EHV_FIVRA_CPU0"
CDS_LIB"logical_power";
"A"3;
%"UNIVERSAL_POWER"
"1","(-4425,1000)","0","logical_power","I20";
;
HDL_POWER"PVCCD_HV_CPU0"
CDS_LIB"logical_power";
"A"4;
%"Q_CAP"
"1","(-4425,1725)","0","pure_quanta","I21";
;
PART_NUMBER"CH647KMEA04"
VALUE"47UF"
VOLTAGE"4V"
TOLERANCE"20%"
PACK_TYPE"C0805"
MATERIAL"X6S"
$LOCATION"C356"
CDS_LIB"pure_quanta"
$LOCATION"C356"
CDS_LOCATION"C356"
$SEC"1"
CDS_SEC"1";
"B"
$PN"2"14;
"A"
$PN"1"5;
%"UNIVERSAL_POWER"
"1","(-4425,2000)","0","logical_power","I22";
;
HDL_POWER"PVCCIN_CPU0"
CDS_LIB"logical_power";
"A"5;
%"Q_CAP"
"1","(-4425,2450)","0","pure_quanta","I23";
;
PART_NUMBER"CH647KMEA04"
VALUE"47UF"
VOLTAGE"4V"
TOLERANCE"20%"
PACK_TYPE"C0805"
MATERIAL"X6S"
$LOCATION"C355"
CDS_LIB"pure_quanta"
$LOCATION"C355"
CDS_LOCATION"C355"
$SEC"1"
CDS_SEC"1";
"B"
$PN"2"17;
"A"
$PN"1"6;
%"UNIVERSAL_POWER"
"1","(-4425,2725)","0","logical_power","I24";
;
HDL_POWER"PVCCIN_CPU0"
CDS_LIB"logical_power";
"A"6;
%"Q_CAP"
"1","(-3975,1725)","0","pure_quanta","I25";
;
PART_NUMBER"CH647KMEA04"
VALUE"47UF"
VOLTAGE"4V"
TOLERANCE"20%"
PACK_TYPE"C0805"
MATERIAL"X6S"
$LOCATION"C359"
CDS_LIB"pure_quanta"
$LOCATION"C359"
CDS_LOCATION"C359"
$SEC"1"
CDS_SEC"1";
"B"
$PN"2"14;
"A"
$PN"1"5;
%"Q_CAP"
"1","(-3525,1725)","0","pure_quanta","I26";
;
PART_NUMBER"CH647KMEA04"
VALUE"47UF"
VOLTAGE"4V"
TOLERANCE"20%"
PACK_TYPE"C0805"
MATERIAL"X6S"
$LOCATION"C362"
CDS_LIB"pure_quanta"
$LOCATION"C362"
CDS_LOCATION"C362"
$SEC"1"
CDS_SEC"1";
"B"
$PN"2"14;
"A"
$PN"1"5;
%"Q_CAP"
"1","(-3975,2450)","0","pure_quanta","I27";
;
PART_NUMBER"CH647KMEA04"
VALUE"47UF"
VOLTAGE"4V"
TOLERANCE"20%"
PACK_TYPE"C0805"
MATERIAL"X6S"
$LOCATION"C358"
CDS_LIB"pure_quanta"
$LOCATION"C358"
CDS_LOCATION"C358"
$SEC"1"
CDS_SEC"1";
"B"
$PN"2"17;
"A"
$PN"1"6;
%"Q_CAP"
"1","(-3525,2450)","0","pure_quanta","I28";
;
PART_NUMBER"CH647KMEA04"
VALUE"47UF"
VOLTAGE"4V"
TOLERANCE"20%"
PACK_TYPE"C0805"
MATERIAL"X6S"
$LOCATION"C361"
CDS_LIB"pure_quanta"
$LOCATION"C361"
CDS_LOCATION"C361"
$SEC"1"
CDS_SEC"1";
"B"
$PN"2"17;
"A"
$PN"1"6;
%"Q_CAP"
"1","(-3075,-1225)","0","pure_quanta","I29";
;
PART_NUMBER"CH622KMEB01"
TOLERANCE"20%"
MATERIAL"X6S"
VOLTAGE"4V"
VALUE"22UF"
PACK_TYPE"C0402"
$LOCATION"C534"
CDS_LIB"pure_quanta"
CDS_LOCATION"C534"
$SEC"1"
CDS_SEC"1";
"B"
$PN"2"11;
"A"
$PN"1"1;
%"Q_CAP"
"1","(-3975,-2225)","0","pure_quanta","I3";
;
PART_NUMBER"CH647KMEA04"
VOLTAGE"4V"
TOLERANCE"20%"
PACK_TYPE"C0805"
VALUE"47UF"
MATERIAL"X6S"
$LOCATION"C497"
CDS_LIB"pure_quanta"
CDS_LOCATION"C497"
$SEC"1"
CDS_SEC"1";
"B"
$PN"2"10;
"A"
$PN"1"3;
%"UNIVERSAL_GND"
"1","(-3075,400)","0","logical_power","I30";
;
CDS_LIB"logical_power"
HDL_POWER"GND";
"A"13;
%"Q_CAP"
"1","(-3075,725)","0","pure_quanta","I31";
;
PART_NUMBER"CH647KMEA04"
TOLERANCE"20%"
VOLTAGE"4V"
VALUE"47UF"
PACK_TYPE"C0805"
MATERIAL"X6S"
$LOCATION"C518"
CDS_LIB"pure_quanta"
CDS_LOCATION"C518"
$SEC"1"
CDS_SEC"1";
"B"
$PN"2"13;
"A"
$PN"1"4;
%"Q_CAP"
"1","(-3075,1725)","0","pure_quanta","I32";
;
PART_NUMBER"CH647KMEA04"
VALUE"47UF"
VOLTAGE"4V"
TOLERANCE"20%"
PACK_TYPE"C0805"
MATERIAL"X6S"
$LOCATION"C365"
CDS_LIB"pure_quanta"
$LOCATION"C365"
CDS_LOCATION"C365"
$SEC"1"
CDS_SEC"1";
"B"
$PN"2"14;
"A"
$PN"1"5;
%"Q_CAP"
"1","(-2625,1725)","0","pure_quanta","I33";
;
PART_NUMBER"CH647KMEA04"
VALUE"47UF"
VOLTAGE"4V"
TOLERANCE"20%"
PACK_TYPE"C0805"
MATERIAL"X6S"
$LOCATION"C368"
CDS_LIB"pure_quanta"
$LOCATION"C368"
CDS_LOCATION"C368"
$SEC"1"
CDS_SEC"1";
"B"
$PN"2"14;
"A"
$PN"1"5;
%"Q_CAP"
"1","(-3075,2450)","0","pure_quanta","I34";
;
PART_NUMBER"CH647KMEA04"
VALUE"47UF"
VOLTAGE"4V"
TOLERANCE"20%"
PACK_TYPE"C0805"
MATERIAL"X6S"
$LOCATION"C364"
CDS_LIB"pure_quanta"
$LOCATION"C364"
CDS_LOCATION"C364"
$SEC"1"
CDS_SEC"1";
"B"
$PN"2"17;
"A"
$PN"1"6;
%"Q_CAP"
"1","(-2625,2450)","0","pure_quanta","I35";
;
PART_NUMBER"CH647KMEA04"
VALUE"47UF"
VOLTAGE"4V"
TOLERANCE"20%"
PACK_TYPE"C0805"
MATERIAL"X6S"
$LOCATION"C367"
CDS_LIB"pure_quanta"
$LOCATION"C367"
CDS_LOCATION"C367"
$SEC"1"
CDS_SEC"1";
"B"
$PN"2"17;
"A"
$PN"1"6;
%"Q_CAP"
"1","(-2175,1725)","0","pure_quanta","I36";
;
PART_NUMBER"CH647KMEA04"
VALUE"47UF"
VOLTAGE"4V"
TOLERANCE"20%"
PACK_TYPE"C0805"
MATERIAL"X6S"
$LOCATION"C371"
CDS_LIB"pure_quanta"
$LOCATION"C371"
CDS_LOCATION"C371"
$SEC"1"
CDS_SEC"1";
"B"
$PN"2"14;
"A"
$PN"1"5;
%"Q_CAP"
"1","(-1725,1725)","0","pure_quanta","I37";
;
PART_NUMBER"CH647KMEA04"
VALUE"47UF"
VOLTAGE"4V"
TOLERANCE"20%"
PACK_TYPE"C0805"
MATERIAL"X6S"
$LOCATION"C397"
CDS_LIB"pure_quanta"
CDS_LOCATION"C397"
$SEC"1"
CDS_SEC"1";
"B"
$PN"2"14;
"A"
$PN"1"5;
%"Q_CAP"
"1","(-1275,1725)","0","pure_quanta","I38";
;
PART_NUMBER"CH647KMEA04"
PACK_TYPE"C0805"
VALUE"47UF"
VOLTAGE"4V"
TOLERANCE"20%"
MATERIAL"X6S"
$LOCATION"C357"
CDS_LIB"pure_quanta"
CDS_LOCATION"C357"
$SEC"1"
CDS_SEC"1";
"B"
$PN"2"14;
"A"
$PN"1"5;
%"Q_CAP"
"1","(-2175,2450)","0","pure_quanta","I39";
;
PART_NUMBER"CH647KMEA04"
VALUE"47UF"
VOLTAGE"4V"
TOLERANCE"20%"
PACK_TYPE"C0805"
MATERIAL"X6S"
$LOCATION"C370"
CDS_LIB"pure_quanta"
$LOCATION"C370"
CDS_LOCATION"C370"
$SEC"1"
CDS_SEC"1";
"B"
$PN"2"17;
"A"
$PN"1"6;
%"Q_CAP"
"1","(-3525,-2225)","0","pure_quanta","I4";
;
PART_NUMBER"CH647KMEA04"
VOLTAGE"4V"
VALUE"47UF"
TOLERANCE"20%"
MATERIAL"X6S"
PACK_TYPE"C0805"
$LOCATION"C501"
CDS_LIB"pure_quanta"
CDS_LOCATION"C501"
$SEC"1"
CDS_SEC"1";
"B"
$PN"2"10;
"A"
$PN"1"3;
%"Q_CAP"
"1","(-1725,2450)","0","pure_quanta","I40";
;
PART_NUMBER"CH647KMEA04"
VALUE"47UF"
VOLTAGE"4V"
TOLERANCE"20%"
PACK_TYPE"C0805"
MATERIAL"X6S"
$LOCATION"C373"
CDS_LIB"pure_quanta"
$LOCATION"C373"
CDS_LOCATION"C373"
$SEC"1"
CDS_SEC"1";
"B"
$PN"2"17;
"A"
$PN"1"6;
%"Q_CAP"
"1","(-1275,2450)","0","pure_quanta","I41";
;
PART_NUMBER"CH647KMEA04"
VALUE"47UF"
VOLTAGE"4V"
TOLERANCE"20%"
PACK_TYPE"C0805"
MATERIAL"X6S"
$LOCATION"C376"
CDS_LIB"pure_quanta"
$LOCATION"C376"
CDS_LOCATION"C376"
$SEC"1"
CDS_SEC"1";
"B"
$PN"2"17;
"A"
$PN"1"6;
%"UNIVERSAL_POWER"
"1","(325,-950)","0","logical_power","I42";
;
HDL_POWER"PVPP_HBM_CPU0"
CDS_LIB"logical_power";
"A"7;
%"Q_CAP"
"1","(325,-1225)","0","pure_quanta","I43";
;
PART_NUMBER"CH647KMEA04"
TOLERANCE"20%"
PACK_TYPE"C0805"
VALUE"47UF"
VOLTAGE"4V"
MATERIAL"X6S"
$LOCATION"C1396"
CDS_LIB"pure_quanta"
CDS_LOCATION"C1396"
$SEC"1"
CDS_SEC"1";
"B"
$PN"2"15;
"A"
$PN"1"7;
%"Q_CAP"
"1","(775,-1225)","0","pure_quanta","I44";
;
PART_NUMBER"CH647KMEA04"
VALUE"47UF"
VOLTAGE"4V"
TOLERANCE"20%"
PACK_TYPE"C0805"
MATERIAL"X6S"
$LOCATION"C1397"
CDS_LIB"pure_quanta"
CDS_LOCATION"C1397"
$SEC"1"
CDS_SEC"1";
"B"
$PN"2"15;
"A"
$PN"1"7;
%"UNIVERSAL_POWER"
"1","(325,100)","0","logical_power","I45";
;
HDL_POWER"PVNN_MAIN_CPU0"
CDS_LIB"logical_power";
"A"8;
%"Q_CAP"
"1","(325,-175)","0","pure_quanta","I46";
;
PART_NUMBER"CH647KMEA04"
PACK_TYPE"C0805"
VALUE"47UF"
VOLTAGE"4V"
MATERIAL"X6S"
TOLERANCE"20%"
$LOCATION"C395"
CDS_LIB"pure_quanta"
$LOCATION"C395"
CDS_LOCATION"C395"
$SEC"1"
CDS_SEC"1";
"B"
$PN"2"16;
"A"
$PN"1"8;
%"Q_CAP"
"1","(775,-175)","0","pure_quanta","I47";
;
PART_NUMBER"CH647LME900"
VALUE"47UF"
VOLTAGE"2.5V"
TOLERANCE"20%"
PACK_TYPE"C0603"
MATERIAL"X6S"
$LOCATION"C1405"
CDS_LIB"pure_quanta"
CDS_LOCATION"C1405"
$SEC"1"
CDS_SEC"1";
"B"
$PN"2"16;
"A"
$PN"1"8;
%"Q_CAP"
"1","(-825,1725)","0","pure_quanta","I48";
;
PART_NUMBER"CH647KMEA04"
VALUE"47UF"
VOLTAGE"4V"
TOLERANCE"20%"
PACK_TYPE"C0805"
MATERIAL"X6S"
$LOCATION"C389"
CDS_LIB"pure_quanta"
$LOCATION"C389"
CDS_LOCATION"C389"
$SEC"1"
CDS_SEC"1";
"B"
$PN"2"14;
"A"
$PN"1"5;
%"Q_CAP"
"1","(-375,1725)","0","pure_quanta","I49";
;
PART_NUMBER"CH647KMEA04"
TOLERANCE"20%"
VALUE"47UF"
VOLTAGE"4V"
PACK_TYPE"C0805"
MATERIAL"X6S"
$LOCATION"C391"
CDS_LIB"pure_quanta"
$LOCATION"C391"
CDS_LOCATION"C391"
$SEC"1"
CDS_SEC"1";
"B"
$PN"2"14;
"A"
$PN"1"5;
%"UNIVERSAL_GND"
"1","(-2625,-2575)","0","logical_power","I5";
;
CDS_LIB"logical_power"
HDL_POWER"GND";
"A"10;
%"Q_CAP"
"1","(-825,2450)","0","pure_quanta","I50";
;
PART_NUMBER"CH647KMEA04"
VALUE"47UF"
VOLTAGE"4V"
TOLERANCE"20%"
PACK_TYPE"C0805"
MATERIAL"X6S"
$LOCATION"C379"
CDS_LIB"pure_quanta"
$LOCATION"C379"
CDS_LOCATION"C379"
$SEC"1"
CDS_SEC"1";
"B"
$PN"2"17;
"A"
$PN"1"6;
%"Q_CAP"
"1","(-375,2450)","0","pure_quanta","I51";
;
PART_NUMBER"CH647KMEA04"
VALUE"47UF"
VOLTAGE"4V"
TOLERANCE"20%"
PACK_TYPE"C0805"
MATERIAL"X6S"
$LOCATION"C382"
CDS_LIB"pure_quanta"
$LOCATION"C382"
CDS_LOCATION"C382"
$SEC"1"
CDS_SEC"1";
"B"
$PN"2"17;
"A"
$PN"1"6;
%"Q_CAP"
"1","(75,1725)","0","pure_quanta","I52";
;
PART_NUMBER"CH647KMEA04"
VALUE"47UF"
VOLTAGE"4V"
TOLERANCE"20%"
PACK_TYPE"C0805"
MATERIAL"X6S"
$LOCATION"C393"
CDS_LIB"pure_quanta"
$LOCATION"C393"
CDS_LOCATION"C393"
$SEC"1"
CDS_SEC"1";
"B"
$PN"2"14;
"A"
$PN"1"5;
%"UNIVERSAL_GND"
"1","(525,1375)","0","logical_power","I53";
;
CDS_LIB"logical_power"
HDL_POWER"GND";
"A"14;
%"Q_CAP"
"1","(525,1725)","0","pure_quanta","I54";
;
PART_NUMBER"CH647KMEA04"
VOLTAGE"4V"
TOLERANCE"20%"
VALUE"47UF"
PACK_TYPE"C0805"
MATERIAL"X6S"
$LOCATION"C360"
CDS_LIB"pure_quanta"
CDS_LOCATION"C360"
$SEC"1"
CDS_SEC"1";
"B"
$PN"2"14;
"A"
$PN"1"5;
%"Q_CAP"
"1","(75,2450)","0","pure_quanta","I55";
;
PART_NUMBER"CH647KMEA04"
VALUE"47UF"
VOLTAGE"4V"
TOLERANCE"20%"
PACK_TYPE"C0805"
MATERIAL"X6S"
$LOCATION"C385"
CDS_LIB"pure_quanta"
$LOCATION"C385"
CDS_LOCATION"C385"
$SEC"1"
CDS_SEC"1";
"B"
$PN"2"17;
"A"
$PN"1"6;
%"Q_CAP"
"1","(525,2450)","0","pure_quanta","I56";
;
PART_NUMBER"CH647KMEA04"
VALUE"47UF"
VOLTAGE"4V"
TOLERANCE"20%"
PACK_TYPE"C0805"
MATERIAL"X6S"
$LOCATION"C387"
CDS_LIB"pure_quanta"
$LOCATION"C387"
CDS_LOCATION"C387"
$SEC"1"
CDS_SEC"1";
"B"
$PN"2"17;
"A"
$PN"1"6;
%"UNIVERSAL_GND"
"1","(1675,-1575)","0","logical_power","I57";
;
CDS_LIB"logical_power"
HDL_POWER"GND";
"A"15;
%"Q_CAP"
"1","(1225,-1225)","0","pure_quanta","I58";
;
PART_NUMBER"CH647KMEA04"
VALUE"47UF"
VOLTAGE"4V"
TOLERANCE"20%"
MATERIAL"X6S"
PACK_TYPE"C0805"
$LOCATION"C1398"
CDS_LIB"pure_quanta"
CDS_LOCATION"C1398"
$SEC"1"
CDS_SEC"1";
"B"
$PN"2"15;
"A"
$PN"1"7;
%"Q_CAP"
"1","(1675,-1225)","0","pure_quanta","I59";
;
PART_NUMBER"CH4221KEE00"
VALUE"0.22UF"
MATERIAL"X6S"
VOLTAGE"6.3V"
TOLERANCE"10%"
PACK_TYPE"C0201"
$LOCATION"C1436"
CDS_LIB"pure_quanta"
CDS_LOCATION"C1436"
$SEC"1"
CDS_SEC"1";
"B"
$PN"2"15;
"A"
$PN"1"7;
%"Q_CAP"
"1","(-3075,-2225)","0","pure_quanta","I6";
;
PART_NUMBER"CH647KMEA04"
VOLTAGE"4V"
TOLERANCE"20%"
PACK_TYPE"C0805"
VALUE"47UF"
MATERIAL"X6S"
$LOCATION"C505"
CDS_LIB"pure_quanta"
CDS_LOCATION"C505"
$SEC"1"
CDS_SEC"1";
"B"
$PN"2"10;
"A"
$PN"1"3;
%"UNIVERSAL_GND"
"1","(1675,-525)","0","logical_power","I60";
;
CDS_LIB"logical_power"
HDL_POWER"GND";
"A"16;
%"Q_CAP"
"1","(1225,-175)","0","pure_quanta","I61";
;
PART_NUMBER"CH647LME900"
VALUE"47UF"
VOLTAGE"2.5V"
TOLERANCE"20%"
PACK_TYPE"C0603"
MATERIAL"X6S"
$LOCATION"C1406"
CDS_LIB"pure_quanta"
CDS_LOCATION"C1406"
$SEC"1"
CDS_SEC"1";
"B"
$PN"2"16;
"A"
$PN"1"8;
%"Q_CAP"
"1","(1675,-175)","0","pure_quanta","I62";
;
PART_NUMBER"CH647LME900"
VOLTAGE"2.5V"
VALUE"47UF"
TOLERANCE"20%"
PACK_TYPE"C0603"
MATERIAL"X6S"
$LOCATION"C1407"
CDS_LIB"pure_quanta"
CDS_LOCATION"C1407"
$SEC"1"
CDS_SEC"1";
"B"
$PN"2"16;
"A"
$PN"1"8;
%"UNIVERSAL_GND"
"1","(975,2100)","0","logical_power","I63";
;
CDS_LIB"logical_power"
HDL_POWER"GND";
"A"17;
%"Q_CAP"
"1","(975,2450)","0","pure_quanta","I64";
;
PART_NUMBER"CH647KMEA04"
VALUE"47UF"
VOLTAGE"4V"
TOLERANCE"20%"
PACK_TYPE"C0805"
MATERIAL"X6S"
$LOCATION"C363"
CDS_LIB"pure_quanta"
CDS_LOCATION"C363"
$SEC"1"
CDS_SEC"1";
"B"
$PN"2"17;
"A"
$PN"1"6;
%"UNIVERSAL_POWER"
"1","(1550,2700)","0","logical_power","I65";
;
HDL_POWER"PVCCIN_CPU0"
CDS_LIB"logical_power";
"A"9;
%"UNIVERSAL_GND"
"1","(2000,2075)","0","logical_power","I66";
;
CDS_LIB"logical_power"
HDL_POWER"GND";
"A"18;
%"Q_CAP"
"1","(2750,2425)","0","pure_quanta","I67";
;
PART_NUMBER"CH647KMEA04"
TOLERANCE"20%"
VOLTAGE"4V"
PACK_TYPE"C0805"
VALUE"47UF"
MATERIAL"X6S"
$LOCATION"C381"
CDS_LIB"pure_quanta"
CDS_LOCATION"C381"
$SEC"1"
CDS_SEC"1";
"B"
$PN"2"18;
"A"
$PN"1"9;
%"Q_CAP"
"1","(3200,2425)","0","pure_quanta","I68";
;
PART_NUMBER"CH647KMEA04"
TOLERANCE"20%"
VOLTAGE"4V"
PACK_TYPE"C0805"
MATERIAL"X6S"
VALUE"47UF"
$LOCATION"C527"
CDS_LIB"pure_quanta"
CDS_LOCATION"C527"
$SEC"1"
CDS_SEC"1";
"B"
$PN"2"18;
"A"
$PN"1"9;
%"UNIVERSAL_GND"
"1","(-3075,-1575)","0","logical_power","I7";
;
CDS_LIB"logical_power"
HDL_POWER"GND";
"A"11;
%"Q_CAP"
"1","(-2625,-2225)","0","pure_quanta","I8";
;
PART_NUMBER"CH647LME900"
PACK_TYPE"C0603"
VOLTAGE"2.5V"
VALUE"47UF"
TOLERANCE"20%"
MATERIAL"X6S"
$LOCATION"C509"
CDS_LIB"pure_quanta"
CDS_LOCATION"C509"
$SEC"1"
CDS_SEC"1";
"B"
$PN"2"10;
"A"
$PN"1"3;
%"Q_CAP"
"1","(-4425,-1225)","0","pure_quanta","I9";
;
PART_NUMBER"CH647KMEA04"
PACK_TYPE"C0805"
TOLERANCE"20%"
MATERIAL"X6S"
VOLTAGE"4V"
VALUE"47UF"
$LOCATION"C522"
CDS_LIB"pure_quanta"
CDS_LOCATION"C522"
$SEC"1"
CDS_SEC"1";
"B"
$PN"2"11;
"A"
$PN"1"1;
END.
